(kicad_pcb
	(version 20260206)
	(generator "pcbnew")
	(generator_version "10.0")
	(general
		(thickness 1.6)
		(legacy_teardrops no)
	)
	(paper "A4")
	(title_block
		(title "Bryce Canyon_SCC_16316-1_OCP.brd")
		(comment 1 "Bryce Canyon / footprints 480-481 of 1561")
	)
	(layers
		(0 "F.Cu" signal "TOP")
		(4 "In1.Cu" signal "L2GND")
		(6 "In2.Cu" signal "L3")
		(8 "In3.Cu" signal "L4VCC")
		(10 "In4.Cu" signal "L5VCC")
		(12 "In5.Cu" signal "L6")
		(14 "In6.Cu" signal "L7GND")
		(2 "B.Cu" signal "BOTTOM")
		(9 "F.Adhes" user "F.Adhesive")
		(11 "B.Adhes" user "B.Adhesive")
		(13 "F.Paste" user "Package Geometry/Pastemask Top")
		(15 "B.Paste" user "Package Geometry/Pastemask Bottom")
		(5 "F.SilkS" user "Ref Des/Silkscreen Top")
		(7 "B.SilkS" user "Ref Des/Silkscreen Bottom")
		(1 "F.Mask" user "Board Geometry/Soldermask Top")
		(3 "B.Mask" user "Board Geometry/Soldermask Bottom")
		(17 "Dwgs.User" user "User.Drawings")
		(19 "Cmts.User" user "User.Comments")
		(21 "Eco1.User" user "User.Eco1")
		(23 "Eco2.User" user "User.Eco2")
		(25 "Edge.Cuts" user "Board Geometry/Outline")
		(27 "Margin" user)
		(31 "F.CrtYd" user "Package Geometry/Place Bound Top")
		(29 "B.CrtYd" user "Package Geometry/Place Bound Bottom")
		(35 "F.Fab" user "Ref Des/Assembly Top")
		(33 "B.Fab" user "Ref Des/Assembly Bottom")
	)
	(footprint ""
		(layer "F.Cu")
		(at 181.03088 -59.974988)
		(property "Reference" "R219"
			(at 0 0 0)
			(layer "F.SilkS")
			(hide yes)
			(effects
				(font
					(size 1.27 1.27)
				)
			)
		)
		(property "Value" "10KR2F-2-GP"
			(at 0.064008 -3.993896 0)
			(unlocked yes)
			(layer "F.Fab")
			(hide yes)
			(effects
				(font
					(size 1.016 1.016)
					(thickness 0.1524)
				)
			)
		)
		(property "Device Type" "R402H16"
			(at 0.064008 -5.517896 0)
			(unlocked yes)
			(layer "F.Fab")
			(hide yes)
			(effects
				(font
					(size 1.016 1.016)
					(thickness 0.1524)
				)
			)
		)
		(duplicate_pad_numbers_are_jumpers no)
		(fp_line
			(start -0.508 -0.9398)
			(end -0.508 0.9398)
			(stroke
				(width 0.1524)
				(type default)
			)
			(layer "F.SilkS")
		)
		(fp_line
			(start 0.508 -0.9398)
			(end -0.508 -0.9398)
			(stroke
				(width 0.1524)
				(type default)
			)
			(layer "F.SilkS")
		)
		(fp_rect
			(start -0.508 0.9398)
			(end 0.508 -0.9398)
			(stroke
				(width 0)
				(type default)
			)
			(fill no)
			(layer "F.CrtYd")
		)
		(fp_rect
			(start -0.508 0.9398)
			(end 0.508 -0.9398)
			(stroke
				(width 0)
				(type default)
			)
			(fill no)
			(layer "F.Fab")
		)
		(pad "1" smd custom
			(at 0 -0.4445)
			(size 0.1397 0.1397)
			(layers "F.Cu" "F.Mask" "F.Paste")
			(net "P1V8_C")
			(options
				(clearance outline)
				(anchor circle)
			)
			(primitives
				(gr_poly
					(pts
						(arc
							(start -0.1778 -0.2794)
							(mid -0.249642 -0.249642)
							(end -0.2794 -0.1778)
						)
						(arc
							(start -0.2794 0.1778)
							(mid -0.249642 0.249642)
							(end -0.1778 0.2794)
						)
						(arc
							(start 0.1778 0.2794)
							(mid 0.249642 0.249642)
							(end 0.2794 0.1778)
						)
						(arc
							(start 0.2794 -0.1778)
							(mid 0.249642 -0.249642)
							(end 0.1778 -0.2794)
						)
					)
					(width 0)
					(fill yes)
				)
			)
		)
		(pad "2" smd custom
			(at 0 0.4445)
			(size 0.1397 0.1397)
			(layers "F.Cu" "F.Mask" "F.Paste")
			(net "XM_CS0_N")
			(options
				(clearance outline)
				(anchor circle)
			)
			(primitives
				(gr_poly
					(pts
						(arc
							(start -0.1778 -0.2794)
							(mid -0.249642 -0.249642)
							(end -0.2794 -0.1778)
						)
						(arc
							(start -0.2794 0.1778)
							(mid -0.249642 0.249642)
							(end -0.1778 0.2794)
						)
						(arc
							(start 0.1778 0.2794)
							(mid 0.249642 0.249642)
							(end 0.2794 0.1778)
						)
						(arc
							(start 0.2794 -0.1778)
							(mid 0.249642 -0.249642)
							(end 0.1778 -0.2794)
						)
					)
					(width 0)
					(fill yes)
				)
			)
		)
	)
	(footprint ""
		(layer "F.Cu")
		(at 133.14553 -44.702984 180)
		(property "Reference" "C41"
			(at 0 0 180)
			(layer "F.SilkS")
			(hide yes)
			(effects
				(font
					(size 1.27 1.27)
				)
			)
		)
		(property "Value" "SCD01U16V1KX-GP"
			(at -2.8321 -1.7399 180)
			(unlocked yes)
			(layer "F.Fab")
			(hide yes)
			(effects
				(font
					(size 1.016 1.016)
					(thickness 0.1524)
				)
			)
		)
		(property "Device Type" "C0201H13"
			(at -2.8321 -3.2639 180)
			(unlocked yes)
			(layer "F.Fab")
			(hide yes)
			(effects
				(font
					(size 1.016 1.016)
					(thickness 0.1524)
				)
			)
		)
		(duplicate_pad_numbers_are_jumpers no)
		(fp_rect
			(start -0.2794 0.6477)
			(end 0.2794 -0.6477)
			(stroke
				(width 0)
				(type default)
			)
			(fill no)
			(layer "F.CrtYd")
		)
		(fp_rect
			(start -0.2794 0.6477)
			(end 0.2794 -0.6477)
			(stroke
				(width 0)
				(type default)
			)
			(fill no)
			(layer "F.Fab")
		)
		(pad "1" smd custom
			(at 0 -0.2794 180)
			(size 0.0762 0.0762)
			(layers "F.Cu" "F.Mask" "F.Paste")
			(net "PHY_IOC_TO_SCC_43_DP")
			(options
				(clearance outline)
				(anchor circle)
			)
			(primitives
				(gr_poly
					(pts
						(arc
							(start 0.1524 -0.127)
							(mid 0.137521 -0.162921)
							(end 0.1016 -0.1778)
						)
						(arc
							(start -0.1016 -0.1778)
							(mid -0.137521 -0.162921)
							(end -0.1524 -0.127)
						)
						(arc
							(start -0.1524 0.127)
							(mid -0.137521 0.162921)
							(end -0.1016 0.1778)
						)
						(arc
							(start 0.1016 0.1778)
							(mid 0.137521 0.162921)
							(end 0.1524 0.127)
						)
					)
					(width 0)
					(fill yes)
				)
			)
		)
		(pad "2" smd custom
			(at 0 0.2794 180)
			(size 0.0762 0.0762)
			(layers "F.Cu" "F.Mask" "F.Paste")
			(net "PHY_IOC_TO_SCC_C_43_DP")
			(options
				(clearance outline)
				(anchor circle)
			)
			(primitives
				(gr_poly
					(pts
						(arc
							(start 0.1524 -0.127)
							(mid 0.137521 -0.162921)
							(end 0.1016 -0.1778)
						)
						(arc
							(start -0.1016 -0.1778)
							(mid -0.137521 -0.162921)
							(end -0.1524 -0.127)
						)
						(arc
							(start -0.1524 0.127)
							(mid -0.137521 0.162921)
							(end -0.1016 0.1778)
						)
						(arc
							(start 0.1016 0.1778)
							(mid 0.137521 0.162921)
							(end 0.1524 0.127)
						)
					)
					(width 0)
					(fill yes)
				)
			)
		)
	)
)
